# S9S_MB_2U (Grand Teton) — schematic netlist excerpt (pin names and nets, part order shuffled) for the footprints in the layout excerpt that follows; sources: Cadence DE-HDL packaged netlist, KiCad conversion of 03242023_DA0F0TMBIJ0_F0T_Motherboard_J_brd_V01_OCP.brd

C989  Q_CAP  10UF 6.3V 20% X6S  pkg C0402  page 74 : A = PVCCIN_CPU0 ; B = GND
R3576  Q_RES  33.2 1% CHIP  pkg 0402LF  page 172 : A = SMB_INA230_5_3V3AUX_SCL_R ; B = SMB_INA230_5_3V3AUX_SCL_R1
C711  Q_CAP_DIFFBUS  DIFF BUS_0.22UF 6.3V 20% X6S  pkg C0201  page 176 : \1\ = P5E_CPU1_PE0_TX_C_DP<15> ; \2\ = P5E_CPU1_PE0_TX_DP<15>

(kicad_pcb
	(version 20260206)
	(generator "pcbnew")
	(generator_version "10.0")
	(general
		(thickness 1.6)
		(legacy_teardrops no)
	)
	(paper "A4")
	(title_block
		(title "03242023_DA0F0TMBIJ0_F0T_Motherboard_J_brd_V01_OCP.brd")
		(comment 1 "Grand Teton / footprints 1166-1168 of 6105")
	)
	(layers
		(0 "F.Cu" signal "TOP")
		(4 "In1.Cu" signal "GND")
		(6 "In2.Cu" signal "IN1")
		(8 "In3.Cu" signal "GND1")
		(10 "In4.Cu" signal "IN2")
		(12 "In5.Cu" signal "GND2")
		(14 "In6.Cu" signal "IN3")
		(16 "In7.Cu" signal "GND3")
		(18 "In8.Cu" signal "VCC")
		(20 "In9.Cu" signal "VCC1")
		(22 "In10.Cu" signal "GND4")
		(24 "In11.Cu" signal "IN4")
		(26 "In12.Cu" signal "GND5")
		(28 "In13.Cu" signal "IN5")
		(30 "In14.Cu" signal "GND6")
		(32 "In15.Cu" signal "IN6")
		(34 "In16.Cu" signal "GND7")
		(2 "B.Cu" signal "BOTTOM")
		(9 "F.Adhes" user "F.Adhesive")
		(11 "B.Adhes" user "B.Adhesive")
		(13 "F.Paste" user "Package Geometry/Pastemask Top")
		(15 "B.Paste" user "Package Geometry/Pastemask Bottom")
		(5 "F.SilkS" user "Ref Des/Silkscreen Top")
		(7 "B.SilkS" user "Ref Des/Silkscreen Bottom")
		(1 "F.Mask" user "Board Geometry/Soldermask Top")
		(3 "B.Mask" user "Board Geometry/Soldermask Bottom")
		(17 "Dwgs.User" user "User.Drawings")
		(19 "Cmts.User" user "User.Comments")
		(21 "Eco1.User" user "User.Eco1")
		(23 "Eco2.User" user "User.Eco2")
		(25 "Edge.Cuts" user "Board Geometry/Outline")
		(27 "Margin" user)
		(31 "F.CrtYd" user "Package Geometry/Place Bound Top")
		(29 "B.CrtYd" user "Package Geometry/Place Bound Bottom")
		(35 "F.Fab" user "Ref Des/Assembly Top")
		(33 "B.Fab" user "Ref Des/Assembly Bottom")
	)
	(footprint ""
		(layer "F.Cu")
		(at 48.868838 -402.371052 -90)
		(property "Reference" "C711"
			(at 0 0 270)
			(layer "F.SilkS")
			(hide yes)
			(effects
				(font
					(size 1.27 1.27)
				)
			)
		)
		(property "Value" ""
			(at 0 0 270)
			(layer "F.Fab")
			(effects
				(font
					(size 1.27 1.27)
				)
			)
		)
		(duplicate_pad_numbers_are_jumpers no)
		(fp_line
			(start -0.299974 0.150114)
			(end -0.299974 -0.150114)
			(stroke
				(width 0.1)
				(type default)
			)
			(layer "F.Fab")
		)
		(fp_line
			(start 0.299974 0.150114)
			(end -0.299974 0.150114)
			(stroke
				(width 0.1)
				(type default)
			)
			(layer "F.Fab")
		)
		(fp_line
			(start -0.299974 -0.150114)
			(end 0.299974 -0.150114)
			(stroke
				(width 0.1)
				(type default)
			)
			(layer "F.Fab")
		)
		(fp_line
			(start 0.299974 -0.150114)
			(end 0.299974 0.150114)
			(stroke
				(width 0.1)
				(type default)
			)
			(layer "F.Fab")
		)
		(pad "1" smd rect
			(at -0.2667 0 270)
			(size 0.3048 0.381)
			(layers "F.Cu" "F.Mask" "F.Paste")
			(net "P5E_CPU1_PE0_TX_C_DP<15>")
		)
		(pad "2" smd rect
			(at 0.2667 0 270)
			(size 0.3048 0.381)
			(layers "F.Cu" "F.Mask" "F.Paste")
			(net "P5E_CPU1_PE0_TX_DP<15>")
		)
	)
	(footprint ""
		(layer "F.Cu")
		(at 213.54288 -34.508948 180)
		(property "Reference" "R3576"
			(at 0 0 180)
			(layer "F.SilkS")
			(hide yes)
			(effects
				(font
					(size 1.27 1.27)
				)
			)
		)
		(property "Value" ""
			(at 0 0 180)
			(layer "F.Fab")
			(effects
				(font
					(size 1.27 1.27)
				)
			)
		)
		(duplicate_pad_numbers_are_jumpers no)
		(fp_line
			(start 0.7874 0.4064)
			(end -0.7874 0.4064)
			(stroke
				(width 0.1524)
				(type default)
			)
			(layer "F.SilkS")
		)
		(fp_line
			(start 0.7874 -0.4064)
			(end 0.7874 0.4064)
			(stroke
				(width 0.1524)
				(type default)
			)
			(layer "F.SilkS")
		)
		(fp_line
			(start -0.7874 0.4064)
			(end -0.7874 -0.4064)
			(stroke
				(width 0.1524)
				(type default)
			)
			(layer "F.SilkS")
		)
		(fp_line
			(start -0.7874 -0.4064)
			(end 0.7874 -0.4064)
			(stroke
				(width 0.1524)
				(type default)
			)
			(layer "F.SilkS")
		)
		(fp_line
			(start 0.67945 0.3048)
			(end 0.120396 0.3048)
			(stroke
				(width 0.1)
				(type default)
			)
			(layer "F.Fab")
		)
		(fp_line
			(start 0.67945 -0.3048)
			(end 0.67945 0.3048)
			(stroke
				(width 0.1)
				(type default)
			)
			(layer "F.Fab")
		)
		(fp_line
			(start 0.12065 -0.2794)
			(end 0.12065 -0.3048)
			(stroke
				(width 0.1)
				(type default)
			)
			(layer "F.Fab")
		)
		(fp_line
			(start 0.12065 -0.3048)
			(end 0.67945 -0.3048)
			(stroke
				(width 0.1)
				(type default)
			)
			(layer "F.Fab")
		)
		(fp_line
			(start 0.120396 0.3048)
			(end 0.120396 0.2794)
			(stroke
				(width 0.1)
				(type default)
			)
			(layer "F.Fab")
		)
		(fp_line
			(start 0.120396 0.2794)
			(end -0.12065 0.2794)
			(stroke
				(width 0.1)
				(type default)
			)
			(layer "F.Fab")
		)
		(fp_line
			(start -0.12065 0.3048)
			(end -0.67945 0.3048)
			(stroke
				(width 0.1)
				(type default)
			)
			(layer "F.Fab")
		)
		(fp_line
			(start -0.12065 0.2794)
			(end -0.12065 0.3048)
			(stroke
				(width 0.1)
				(type default)
			)
			(layer "F.Fab")
		)
		(fp_line
			(start -0.12065 -0.2794)
			(end 0.12065 -0.2794)
			(stroke
				(width 0.1)
				(type default)
			)
			(layer "F.Fab")
		)
		(fp_line
			(start -0.12065 -0.305054)
			(end -0.12065 -0.2794)
			(stroke
				(width 0.1)
				(type default)
			)
			(layer "F.Fab")
		)
		(fp_line
			(start -0.67945 0.3048)
			(end -0.67945 -0.305054)
			(stroke
				(width 0.1)
				(type default)
			)
			(layer "F.Fab")
		)
		(fp_line
			(start -0.67945 -0.305054)
			(end -0.12065 -0.305054)
			(stroke
				(width 0.1)
				(type default)
			)
			(layer "F.Fab")
		)
		(pad "1" smd circle
			(at -0.40005 0 180)
			(size 0 0)
			(layers "F.Cu" "F.Mask" "F.Paste")
			(net "SMB_INA230_5_3V3AUX_SCL_R")
		)
		(pad "2" smd circle
			(at 0.40005 0 180)
			(size 0 0)
			(layers "F.Cu" "F.Mask" "F.Paste")
			(net "SMB_INA230_5_3V3AUX_SCL_R1")
		)
	)
	(footprint ""
		(layer "F.Cu")
		(at 365.46663 -247.715024 90)
		(property "Reference" "C989"
			(at 0 0 90)
			(layer "F.SilkS")
			(hide yes)
			(effects
				(font
					(size 1.27 1.27)
				)
			)
		)
		(property "Value" ""
			(at 0 0 90)
			(layer "F.Fab")
			(effects
				(font
					(size 1.27 1.27)
				)
			)
		)
		(duplicate_pad_numbers_are_jumpers no)
		(fp_line
			(start 0.7874 -0.4064)
			(end 0.7874 0.4064)
			(stroke
				(width 0.1524)
				(type default)
			)
			(layer "F.SilkS")
		)
		(fp_line
			(start -0.7874 -0.4064)
			(end 0.7874 -0.4064)
			(stroke
				(width 0.1524)
				(type default)
			)
			(layer "F.SilkS")
		)
		(fp_line
			(start 0.7874 0.4064)
			(end -0.7874 0.4064)
			(stroke
				(width 0.1524)
				(type default)
			)
			(layer "F.SilkS")
		)
		(fp_line
			(start -0.7874 0.4064)
			(end -0.7874 -0.4064)
			(stroke
				(width 0.1524)
				(type default)
			)
			(layer "F.SilkS")
		)
		(fp_line
			(start -0.12065 -0.305054)
			(end -0.12065 -0.2794)
			(stroke
				(width 0.1)
				(type default)
			)
			(layer "F.Fab")
		)
		(fp_line
			(start -0.67945 -0.305054)
			(end -0.12065 -0.305054)
			(stroke
				(width 0.1)
				(type default)
			)
			(layer "F.Fab")
		)
		(fp_line
			(start 0.67945 -0.3048)
			(end 0.67945 0.3048)
			(stroke
				(width 0.1)
				(type default)
			)
			(layer "F.Fab")
		)
		(fp_line
			(start 0.12065 -0.3048)
			(end 0.67945 -0.3048)
			(stroke
				(width 0.1)
				(type default)
			)
			(layer "F.Fab")
		)
		(fp_line
			(start 0.12065 -0.2794)
			(end 0.12065 -0.3048)
			(stroke
				(width 0.1)
				(type default)
			)
			(layer "F.Fab")
		)
		(fp_line
			(start -0.12065 -0.2794)
			(end 0.12065 -0.2794)
			(stroke
				(width 0.1)
				(type default)
			)
			(layer "F.Fab")
		)
		(fp_line
			(start 0.120396 0.2794)
			(end -0.12065 0.2794)
			(stroke
				(width 0.1)
				(type default)
			)
			(layer "F.Fab")
		)
		(fp_line
			(start -0.12065 0.2794)
			(end -0.12065 0.3048)
			(stroke
				(width 0.1)
				(type default)
			)
			(layer "F.Fab")
		)
		(fp_line
			(start 0.67945 0.3048)
			(end 0.120396 0.3048)
			(stroke
				(width 0.1)
				(type default)
			)
			(layer "F.Fab")
		)
		(fp_line
			(start 0.120396 0.3048)
			(end 0.120396 0.2794)
			(stroke
				(width 0.1)
				(type default)
			)
			(layer "F.Fab")
		)
		(fp_line
			(start -0.12065 0.3048)
			(end -0.67945 0.3048)
			(stroke
				(width 0.1)
				(type default)
			)
			(layer "F.Fab")
		)
		(fp_line
			(start -0.67945 0.3048)
			(end -0.67945 -0.305054)
			(stroke
				(width 0.1)
				(type default)
			)
			(layer "F.Fab")
		)
		(pad "1" smd circle
			(at -0.40005 0 90)
			(size 0 0)
			(layers "F.Cu" "F.Mask" "F.Paste")
			(net "PVCCIN_CPU0")
		)
		(pad "2" smd circle
			(at 0.40005 0 90)
			(size 0 0)
			(layers "F.Cu" "F.Mask" "F.Paste")
			(net "GND")
		)
	)
)
